# S9S_MB_2U (Grand Teton) — schematic netlist excerpt (pin names and nets, part order shuffled) for the footprints in the layout excerpt that follows; sources: Cadence DE-HDL packaged netlist, KiCad conversion of 03242023_DA0F0TMBIJ0_F0T_Motherboard_J_brd_V01_OCP.brd

R2973  Q_RES  1K 1% EMPTY  pkg 0402LF  page 195 : A = FAB_REV_ID2 ; B = GND
C147  Q_CAP_DIFFBUS  DIFF BUS_0.22UF 6.3V 20% X6S  pkg C0201  page 178 : \1\ = DMI_CPU0_PCH_TX_C_DN<3> ; \2\ = DMI_CPU0_PCH_TX_DN<3>

PL30  Q_INDUCTOR4P_14  150NH IND  pkg L_TLM117513Q-151QL_11X7-5XA  page 285
  \1\  = SW_PVCCIN_CPU1_SW2
  \2\  = IND_P1_CPL2
  \3\  = IND_P1_CPL1
  \4\  = PVCCIN_CPU1

(kicad_pcb
	(version 20260206)
	(generator "pcbnew")
	(generator_version "10.0")
	(general
		(thickness 1.6)
		(legacy_teardrops no)
	)
	(paper "A4")
	(title_block
		(title "03242023_DA0F0TMBIJ0_F0T_Motherboard_J_brd_V01_OCP.brd")
		(comment 1 "Grand Teton / footprints 498-500 of 6105")
	)
	(layers
		(0 "F.Cu" signal "TOP")
		(4 "In1.Cu" signal "GND")
		(6 "In2.Cu" signal "IN1")
		(8 "In3.Cu" signal "GND1")
		(10 "In4.Cu" signal "IN2")
		(12 "In5.Cu" signal "GND2")
		(14 "In6.Cu" signal "IN3")
		(16 "In7.Cu" signal "GND3")
		(18 "In8.Cu" signal "VCC")
		(20 "In9.Cu" signal "VCC1")
		(22 "In10.Cu" signal "GND4")
		(24 "In11.Cu" signal "IN4")
		(26 "In12.Cu" signal "GND5")
		(28 "In13.Cu" signal "IN5")
		(30 "In14.Cu" signal "GND6")
		(32 "In15.Cu" signal "IN6")
		(34 "In16.Cu" signal "GND7")
		(2 "B.Cu" signal "BOTTOM")
		(9 "F.Adhes" user "F.Adhesive")
		(11 "B.Adhes" user "B.Adhesive")
		(13 "F.Paste" user "Package Geometry/Pastemask Top")
		(15 "B.Paste" user "Package Geometry/Pastemask Bottom")
		(5 "F.SilkS" user "Ref Des/Silkscreen Top")
		(7 "B.SilkS" user "Ref Des/Silkscreen Bottom")
		(1 "F.Mask" user "Board Geometry/Soldermask Top")
		(3 "B.Mask" user "Board Geometry/Soldermask Bottom")
		(17 "Dwgs.User" user "User.Drawings")
		(19 "Cmts.User" user "User.Comments")
		(21 "Eco1.User" user "User.Eco1")
		(23 "Eco2.User" user "User.Eco2")
		(25 "Edge.Cuts" user "Board Geometry/Outline")
		(27 "Margin" user)
		(31 "F.CrtYd" user "Package Geometry/Place Bound Top")
		(29 "B.CrtYd" user "Package Geometry/Place Bound Bottom")
		(35 "F.Fab" user "Ref Des/Assembly Top")
		(33 "B.Fab" user "Ref Des/Assembly Bottom")
	)
	(footprint ""
		(layer "F.Cu")
		(at 105.132886 -324.445376)
		(property "Reference" "PL30"
			(at -12.69492 7.099554 90)
			(unlocked yes)
			(layer "F.SilkS")
			(effects
				(font
					(size 0.7874 0.5842)
					(thickness 0.1524)
				)
				(justify left)
			)
		)
		(property "Value" ""
			(at 0 0 0)
			(layer "F.Fab")
			(effects
				(font
					(size 1.27 1.27)
				)
			)
		)
		(duplicate_pad_numbers_are_jumpers no)
		(fp_line
			(start -3.750056 -5.500116)
			(end -2.393442 -5.500116)
			(stroke
				(width 0.1524)
				(type default)
			)
			(layer "F.SilkS")
		)
		(fp_line
			(start -3.750056 5.500116)
			(end -3.750056 -5.500116)
			(stroke
				(width 0.1524)
				(type default)
			)
			(layer "F.SilkS")
		)
		(fp_line
			(start -2.393442 5.500116)
			(end -3.750056 5.500116)
			(stroke
				(width 0.1524)
				(type default)
			)
			(layer "F.SilkS")
		)
		(fp_line
			(start 2.393442 5.500116)
			(end 3.750056 5.500116)
			(stroke
				(width 0.1524)
				(type default)
			)
			(layer "F.SilkS")
		)
		(fp_line
			(start 3.750056 -5.500116)
			(end 2.393442 -5.500116)
			(stroke
				(width 0.1524)
				(type default)
			)
			(layer "F.SilkS")
		)
		(fp_line
			(start 3.750056 5.500116)
			(end 3.750056 -5.500116)
			(stroke
				(width 0.1524)
				(type default)
			)
			(layer "F.SilkS")
		)
		(fp_poly
			(pts
				(xy -3.418586 -6.86943) (xy -3.05943 -5.791708) (xy -4.136898 -6.150864)
			)
			(stroke
				(width 0)
				(type default)
			)
			(fill yes)
			(layer "F.SilkS")
		)
		(fp_line
			(start -3.750056 -5.500116)
			(end -3.750056 5.500116)
			(stroke
				(width 0.1)
				(type default)
			)
			(layer "F.Fab")
		)
		(fp_line
			(start -3.750056 5.500116)
			(end 3.750056 5.500116)
			(stroke
				(width 0.1)
				(type default)
			)
			(layer "F.Fab")
		)
		(fp_line
			(start 3.750056 -5.500116)
			(end -3.750056 -5.500116)
			(stroke
				(width 0.1)
				(type default)
			)
			(layer "F.Fab")
		)
		(fp_line
			(start 3.750056 5.500116)
			(end 3.750056 -5.500116)
			(stroke
				(width 0.1)
				(type default)
			)
			(layer "F.Fab")
		)
		(fp_poly
			(pts
				(xy -4.9276 -4.757928) (xy -4.9276 -3.741928) (xy -3.9116 -4.249928)
			)
			(stroke
				(width 0)
				(type default)
			)
			(fill yes)
			(layer "F.Fab")
		)
		(pad "1" smd rect
			(at 0 -4.249928 270)
			(size 2.413 4.5212)
			(layers "F.Cu" "F.Mask" "F.Paste")
			(net "SW_PVCCIN_CPU1_SW2")
		)
		(pad "2" smd rect
			(at 0 -1.175004 270)
			(size 1.3716 4.5212)
			(layers "F.Cu" "F.Mask" "F.Paste")
			(net "IND_P1_CPL2")
		)
		(pad "3" smd rect
			(at 0 1.175004 270)
			(size 1.3716 4.5212)
			(layers "F.Cu" "F.Mask" "F.Paste")
			(net "IND_P1_CPL1")
		)
		(pad "4" smd rect
			(at 0 4.249928 270)
			(size 2.413 4.5212)
			(layers "F.Cu" "F.Mask" "F.Paste")
			(net "PVCCIN_CPU1")
		)
	)
	(footprint ""
		(layer "F.Cu")
		(at 349.014034 -68.21678)
		(property "Reference" "C147"
			(at 0 0 0)
			(layer "F.SilkS")
			(hide yes)
			(effects
				(font
					(size 1.27 1.27)
				)
			)
		)
		(property "Value" ""
			(at 0 0 0)
			(layer "F.Fab")
			(effects
				(font
					(size 1.27 1.27)
				)
			)
		)
		(duplicate_pad_numbers_are_jumpers no)
		(fp_line
			(start -0.299974 -0.150114)
			(end 0.299974 -0.150114)
			(stroke
				(width 0.1)
				(type default)
			)
			(layer "F.Fab")
		)
		(fp_line
			(start -0.299974 0.150114)
			(end -0.299974 -0.150114)
			(stroke
				(width 0.1)
				(type default)
			)
			(layer "F.Fab")
		)
		(fp_line
			(start 0.299974 -0.150114)
			(end 0.299974 0.150114)
			(stroke
				(width 0.1)
				(type default)
			)
			(layer "F.Fab")
		)
		(fp_line
			(start 0.299974 0.150114)
			(end -0.299974 0.150114)
			(stroke
				(width 0.1)
				(type default)
			)
			(layer "F.Fab")
		)
		(pad "1" smd rect
			(at -0.2667 0)
			(size 0.3048 0.381)
			(layers "F.Cu" "F.Mask" "F.Paste")
			(net "DMI_CPU0_PCH_TX_C_DN<3>")
		)
		(pad "2" smd rect
			(at 0.2667 0)
			(size 0.3048 0.381)
			(layers "F.Cu" "F.Mask" "F.Paste")
			(net "DMI_CPU0_PCH_TX_DN<3>")
		)
	)
	(footprint ""
		(layer "F.Cu")
		(at 299.02023 -48.304196 180)
		(property "Reference" "R2973"
			(at 0 0 180)
			(layer "F.SilkS")
			(hide yes)
			(effects
				(font
					(size 1.27 1.27)
				)
			)
		)
		(property "Value" ""
			(at 0 0 180)
			(layer "F.Fab")
			(effects
				(font
					(size 1.27 1.27)
				)
			)
		)
		(duplicate_pad_numbers_are_jumpers no)
		(fp_line
			(start 0.7874 0.4064)
			(end -0.7874 0.4064)
			(stroke
				(width 0.1524)
				(type default)
			)
			(layer "F.SilkS")
		)
		(fp_line
			(start 0.7874 -0.4064)
			(end 0.7874 0.4064)
			(stroke
				(width 0.1524)
				(type default)
			)
			(layer "F.SilkS")
		)
		(fp_line
			(start -0.7874 0.4064)
			(end -0.7874 -0.4064)
			(stroke
				(width 0.1524)
				(type default)
			)
			(layer "F.SilkS")
		)
		(fp_line
			(start -0.7874 -0.4064)
			(end 0.7874 -0.4064)
			(stroke
				(width 0.1524)
				(type default)
			)
			(layer "F.SilkS")
		)
		(fp_line
			(start 0.67945 0.3048)
			(end 0.120396 0.3048)
			(stroke
				(width 0.1)
				(type default)
			)
			(layer "F.Fab")
		)
		(fp_line
			(start 0.67945 -0.3048)
			(end 0.67945 0.3048)
			(stroke
				(width 0.1)
				(type default)
			)
			(layer "F.Fab")
		)
		(fp_line
			(start 0.12065 -0.2794)
			(end 0.12065 -0.3048)
			(stroke
				(width 0.1)
				(type default)
			)
			(layer "F.Fab")
		)
		(fp_line
			(start 0.12065 -0.3048)
			(end 0.67945 -0.3048)
			(stroke
				(width 0.1)
				(type default)
			)
			(layer "F.Fab")
		)
		(fp_line
			(start 0.120396 0.3048)
			(end 0.120396 0.2794)
			(stroke
				(width 0.1)
				(type default)
			)
			(layer "F.Fab")
		)
		(fp_line
			(start 0.120396 0.2794)
			(end -0.12065 0.2794)
			(stroke
				(width 0.1)
				(type default)
			)
			(layer "F.Fab")
		)
		(fp_line
			(start -0.12065 0.3048)
			(end -0.67945 0.3048)
			(stroke
				(width 0.1)
				(type default)
			)
			(layer "F.Fab")
		)
		(fp_line
			(start -0.12065 0.2794)
			(end -0.12065 0.3048)
			(stroke
				(width 0.1)
				(type default)
			)
			(layer "F.Fab")
		)
		(fp_line
			(start -0.12065 -0.2794)
			(end 0.12065 -0.2794)
			(stroke
				(width 0.1)
				(type default)
			)
			(layer "F.Fab")
		)
		(fp_line
			(start -0.12065 -0.305054)
			(end -0.12065 -0.2794)
			(stroke
				(width 0.1)
				(type default)
			)
			(layer "F.Fab")
		)
		(fp_line
			(start -0.67945 0.3048)
			(end -0.67945 -0.305054)
			(stroke
				(width 0.1)
				(type default)
			)
			(layer "F.Fab")
		)
		(fp_line
			(start -0.67945 -0.305054)
			(end -0.12065 -0.305054)
			(stroke
				(width 0.1)
				(type default)
			)
			(layer "F.Fab")
		)
		(pad "1" smd circle
			(at -0.40005 0 180)
			(size 0 0)
			(layers "F.Cu" "F.Mask" "F.Paste")
			(net "FAB_REV_ID2")
		)
		(pad "2" smd circle
			(at 0.40005 0 180)
			(size 0 0)
			(layers "F.Cu" "F.Mask" "F.Paste")
			(net "GND")
		)
	)
)
